(kicad_pcb
	(version 20260206)
	(generator "pcbnew")
	(generator_version "10.0")
	(general
		(thickness 1.6)
		(legacy_teardrops no)
	)
	(paper "A4")
	(title_block
		(title "v1-chassis-manager — T6M_CM_d_v01_1031_1645.brd")
		(comment 1 "Open CloudServer (Microsoft) / footprints 736-743 of 2512")
	)
	(layers
		(0 "F.Cu" signal "TOP")
		(4 "In1.Cu" signal "GND1")
		(6 "In2.Cu" signal "IN1")
		(8 "In3.Cu" signal "VCC1")
		(10 "In4.Cu" signal "VCC2")
		(12 "In5.Cu" signal "GND2")
		(14 "In6.Cu" signal "IN2")
		(16 "In7.Cu" signal "IN3")
		(18 "In8.Cu" signal "GND3")
		(2 "B.Cu" signal "BOTTOM")
		(9 "F.Adhes" user "F.Adhesive")
		(11 "B.Adhes" user "B.Adhesive")
		(13 "F.Paste" user "Package Geometry/Pastemask Top")
		(15 "B.Paste" user "Package Geometry/Pastemask Bottom")
		(5 "F.SilkS" user "Ref Des/Silkscreen Top")
		(7 "B.SilkS" user "Ref Des/Silkscreen Bottom")
		(1 "F.Mask" user "Board Geometry/Soldermask Top")
		(3 "B.Mask" user "Board Geometry/Soldermask Bottom")
		(17 "Dwgs.User" user "User.Drawings")
		(19 "Cmts.User" user "User.Comments")
		(21 "Eco1.User" user "User.Eco1")
		(23 "Eco2.User" user "User.Eco2")
		(25 "Edge.Cuts" user "Board Geometry/Outline")
		(27 "Margin" user)
		(31 "F.CrtYd" user "Package Geometry/Place Bound Top")
		(29 "B.CrtYd" user "Package Geometry/Place Bound Bottom")
		(35 "F.Fab" user "Ref Des/Assembly Top")
		(33 "B.Fab" user "Ref Des/Assembly Bottom")
	)
	(footprint ""
		(layer "F.Cu")
		(at 180.1876 -188.4172 -90)
		(property "Reference" "R1294"
			(at -1.1176 0.02413 90)
			(unlocked yes)
			(layer "F.SilkS")
			(effects
				(font
					(size 0.7874 0.5842)
					(thickness 0.1524)
				)
				(justify left)
			)
		)
		(property "Value" ""
			(at 0 0 270)
			(layer "F.Fab")
			(effects
				(font
					(size 1.27 1.27)
				)
			)
		)
		(duplicate_pad_numbers_are_jumpers no)
		(fp_line
			(start -0.7874 0.4064)
			(end -0.7874 -0.4064)
			(stroke
				(width 0.1524)
				(type default)
			)
			(layer "F.SilkS")
		)
		(fp_line
			(start 0.7874 0.4064)
			(end -0.7874 0.4064)
			(stroke
				(width 0.1524)
				(type default)
			)
			(layer "F.SilkS")
		)
		(fp_line
			(start -0.7874 -0.4064)
			(end 0.7874 -0.4064)
			(stroke
				(width 0.1524)
				(type default)
			)
			(layer "F.SilkS")
		)
		(fp_line
			(start 0.7874 -0.4064)
			(end 0.7874 0.4064)
			(stroke
				(width 0.1524)
				(type default)
			)
			(layer "F.SilkS")
		)
		(fp_poly
			(pts
				(xy -0.508 0.2794) (xy -0.508 0.2286) (xy -0.635 0.2286) (xy -0.635 -0.254) (xy -0.5334 -0.254)
				(xy -0.5334 -0.2794) (xy 0.5334 -0.2794) (xy 0.5334 -0.254) (xy 0.635 -0.254) (xy 0.635 0.254) (xy 0.5334 0.254)
				(xy 0.5334 0.2794)
			)
			(stroke
				(width 0)
				(type default)
			)
			(fill no)
			(layer "F.CrtYd")
		)
		(pad "1" smd rect
			(at 0.40005 0 270)
			(size 0.4572 0.508)
			(layers "F.Cu" "F.Mask" "F.Paste")
			(net "POWER_SW1_PWR_CTR_12V")
		)
		(pad "2" smd rect
			(at -0.40005 0 270)
			(size 0.4572 0.508)
			(layers "F.Cu" "F.Mask" "F.Paste")
			(net "POWER_SW1_PWR_CTR_12V_R")
		)
	)
	(footprint ""
		(layer "F.Cu")
		(at 17.874996 -62.977776 90)
		(property "Reference" "Q17"
			(at 0.419862 3.758946 90)
			(unlocked yes)
			(layer "F.SilkS")
			(effects
				(font
					(size 0.7874 0.5842)
					(thickness 0.1524)
				)
			)
		)
		(property "Value" ""
			(at 0 0 90)
			(layer "F.Fab")
			(effects
				(font
					(size 1.27 1.27)
				)
			)
		)
		(duplicate_pad_numbers_are_jumpers no)
		(fp_line
			(start 1.651 -1.905)
			(end 1.651 1.905)
			(stroke
				(width 0.1524)
				(type default)
			)
			(layer "F.SilkS")
		)
		(fp_line
			(start -1.651 -1.905)
			(end 1.651 -1.905)
			(stroke
				(width 0.1524)
				(type default)
			)
			(layer "F.SilkS")
		)
		(fp_line
			(start 1.651 1.905)
			(end -1.651 1.905)
			(stroke
				(width 0.1524)
				(type default)
			)
			(layer "F.SilkS")
		)
		(fp_line
			(start -1.651 1.905)
			(end -1.651 -1.905)
			(stroke
				(width 0.1524)
				(type default)
			)
			(layer "F.SilkS")
		)
		(fp_poly
			(pts
				(xy -1.524 0.7112) (xy -1.524 1.7526) (xy -0.508 1.7526) (xy -0.508 0.6985) (xy 0.508 0.6985) (xy 0.508 1.7526)
				(xy 1.524 1.7526) (xy 1.524 0.6985) (xy 1.524 -0.6985) (xy 0.508 -0.6985) (xy 0.508 -1.7526) (xy -0.508 -1.7526)
				(xy -0.508 -0.6985) (xy -1.524 -0.6985) (xy -1.524 0.6985)
			)
			(stroke
				(width 0)
				(type default)
			)
			(fill no)
			(layer "F.CrtYd")
		)
		(fp_text user "S"
			(at 2.184146 -1.873504 0)
			(unlocked yes)
			(layer "F.SilkS")
			(effects
				(font
					(size 0.635 0.4064)
					(thickness 0.1524)
				)
			)
		)
		(fp_text user "D"
			(at -1.168908 -1.606296 0)
			(unlocked yes)
			(layer "F.SilkS")
			(effects
				(font
					(size 0.635 0.4064)
					(thickness 0.1524)
				)
			)
		)
		(fp_text user "G"
			(at -1.901444 2.389378 0)
			(unlocked yes)
			(layer "F.SilkS")
			(effects
				(font
					(size 0.635 0.4064)
					(thickness 0.1524)
				)
			)
		)
		(pad "D" smd rect
			(at 0 -1.1176 90)
			(size 1.016 1.27)
			(layers "F.Cu" "F.Mask" "F.Paste")
			(net "I2C_VIDREAR_5V_SCL")
		)
		(pad "G" smd rect
			(at -1.016 1.1176 90)
			(size 1.016 1.27)
			(layers "F.Cu" "F.Mask" "F.Paste")
			(net "N21581283")
		)
		(pad "S" smd rect
			(at 1.016 1.1176 90)
			(size 1.016 1.27)
			(layers "F.Cu" "F.Mask" "F.Paste")
			(net "SMB_BMC_NODE1_DDC_CLK")
		)
	)
	(footprint ""
		(layer "F.Cu")
		(at 18.231612 -54.254654 90)
		(property "Reference" "R659"
			(at -3.358896 13.863574 90)
			(unlocked yes)
			(layer "F.SilkS")
			(effects
				(font
					(size 0.7874 0.5842)
					(thickness 0.1524)
				)
				(justify left)
			)
		)
		(property "Value" ""
			(at 0 0 90)
			(layer "F.Fab")
			(effects
				(font
					(size 1.27 1.27)
				)
			)
		)
		(duplicate_pad_numbers_are_jumpers no)
		(fp_line
			(start 0.7874 -0.4064)
			(end 0.7874 0.4064)
			(stroke
				(width 0.1524)
				(type default)
			)
			(layer "F.SilkS")
		)
		(fp_line
			(start -0.7874 -0.4064)
			(end 0.7874 -0.4064)
			(stroke
				(width 0.1524)
				(type default)
			)
			(layer "F.SilkS")
		)
		(fp_line
			(start 0.7874 0.4064)
			(end -0.7874 0.4064)
			(stroke
				(width 0.1524)
				(type default)
			)
			(layer "F.SilkS")
		)
		(fp_line
			(start -0.7874 0.4064)
			(end -0.7874 -0.4064)
			(stroke
				(width 0.1524)
				(type default)
			)
			(layer "F.SilkS")
		)
		(fp_poly
			(pts
				(xy -0.508 0.2794) (xy -0.508 0.2286) (xy -0.635 0.2286) (xy -0.635 -0.254) (xy -0.5334 -0.254)
				(xy -0.5334 -0.2794) (xy 0.5334 -0.2794) (xy 0.5334 -0.254) (xy 0.635 -0.254) (xy 0.635 0.254) (xy 0.5334 0.254)
				(xy 0.5334 0.2794)
			)
			(stroke
				(width 0)
				(type default)
			)
			(fill no)
			(layer "F.CrtYd")
		)
		(pad "1" smd rect
			(at 0.40005 0 90)
			(size 0.4572 0.508)
			(layers "F.Cu" "F.Mask" "F.Paste")
			(net "CRT_B_L")
		)
		(pad "2" smd rect
			(at -0.40005 0 90)
			(size 0.4572 0.508)
			(layers "F.Cu" "F.Mask" "F.Paste")
			(net "CRT_B")
		)
	)
	(footprint ""
		(layer "F.Cu")
		(at 16.686784 -43.934634 -90)
		(property "Reference" "L41"
			(at 8.057134 1.275588 90)
			(unlocked yes)
			(layer "F.SilkS")
			(effects
				(font
					(size 0.7874 0.5842)
					(thickness 0.1524)
				)
			)
		)
		(property "Value" ""
			(at 0 0 270)
			(layer "F.Fab")
			(effects
				(font
					(size 1.27 1.27)
				)
			)
		)
		(duplicate_pad_numbers_are_jumpers no)
		(fp_line
			(start 1.2954 0.635)
			(end -1.2954 0.635)
			(stroke
				(width 0.1524)
				(type default)
			)
			(layer "F.SilkS")
		)
		(fp_line
			(start -0.127 -0.5842)
			(end -0.127 0.5842)
			(stroke
				(width 0.1524)
				(type default)
			)
			(layer "F.SilkS")
		)
		(fp_line
			(start 0.127 -0.5842)
			(end 0.127 0.5842)
			(stroke
				(width 0.1524)
				(type default)
			)
			(layer "F.SilkS")
		)
		(fp_line
			(start -1.2954 -0.635)
			(end -1.2954 0.635)
			(stroke
				(width 0.1524)
				(type default)
			)
			(layer "F.SilkS")
		)
		(fp_line
			(start -1.2954 -0.635)
			(end 1.2954 -0.635)
			(stroke
				(width 0.1524)
				(type default)
			)
			(layer "F.SilkS")
		)
		(fp_line
			(start 1.2954 -0.635)
			(end 1.2954 0.635)
			(stroke
				(width 0.1524)
				(type default)
			)
			(layer "F.SilkS")
		)
		(fp_poly
			(pts
				(xy -0.9144 0.508) (xy -0.9144 0.3556) (xy -1.143 0.3556) (xy -1.143 -0.3556) (xy -0.9144 -0.3556)
				(xy -0.9144 -0.508) (xy 0.9144 -0.508) (xy 0.9144 -0.3556) (xy 1.143 -0.3556) (xy 1.143 0.3556)
				(xy 0.9144 0.3556) (xy 0.9144 0.508)
			)
			(stroke
				(width 0)
				(type default)
			)
			(fill no)
			(layer "F.CrtYd")
		)
		(pad "1" smd rect
			(at 0.7366 0)
			(size 0.7112 0.8128)
			(layers "F.Cu" "F.Mask" "F.Paste")
			(net "BMC_NODE1_GFX_RED")
		)
		(pad "2" smd rect
			(at -0.7366 0)
			(size 0.7112 0.8128)
			(layers "F.Cu" "F.Mask" "F.Paste")
			(net "CRT_R_L")
		)
	)
	(footprint ""
		(layer "F.Cu")
		(at 19.938746 -98.963734 180)
		(property "Reference" "R186"
			(at 5.192776 0.467106 0)
			(unlocked yes)
			(layer "F.SilkS")
			(effects
				(font
					(size 0.7874 0.5842)
					(thickness 0.1524)
				)
				(justify left)
			)
		)
		(property "Value" ""
			(at 0 0 180)
			(layer "F.Fab")
			(effects
				(font
					(size 1.27 1.27)
				)
			)
		)
		(duplicate_pad_numbers_are_jumpers no)
		(fp_line
			(start 0.7874 0.4064)
			(end -0.7874 0.4064)
			(stroke
				(width 0.1524)
				(type default)
			)
			(layer "F.SilkS")
		)
		(fp_line
			(start 0.7874 -0.4064)
			(end 0.7874 0.4064)
			(stroke
				(width 0.1524)
				(type default)
			)
			(layer "F.SilkS")
		)
		(fp_line
			(start -0.7874 0.4064)
			(end -0.7874 -0.4064)
			(stroke
				(width 0.1524)
				(type default)
			)
			(layer "F.SilkS")
		)
		(fp_line
			(start -0.7874 -0.4064)
			(end 0.7874 -0.4064)
			(stroke
				(width 0.1524)
				(type default)
			)
			(layer "F.SilkS")
		)
		(fp_poly
			(pts
				(xy -0.508 0.2794) (xy -0.508 0.2286) (xy -0.635 0.2286) (xy -0.635 -0.254) (xy -0.5334 -0.254)
				(xy -0.5334 -0.2794) (xy 0.5334 -0.2794) (xy 0.5334 -0.254) (xy 0.635 -0.254) (xy 0.635 0.254) (xy 0.5334 0.254)
				(xy 0.5334 0.2794)
			)
			(stroke
				(width 0)
				(type default)
			)
			(fill no)
			(layer "F.CrtYd")
		)
		(pad "1" smd rect
			(at 0.40005 0 180)
			(size 0.4572 0.508)
			(layers "F.Cu" "F.Mask" "F.Paste")
			(net "P3V3_NODE1")
		)
		(pad "2" smd rect
			(at -0.40005 0 180)
			(size 0.4572 0.508)
			(layers "F.Cu" "F.Mask" "F.Paste")
			(net "FRU_SYS_A1")
		)
	)
	(footprint ""
		(layer "F.Cu")
		(at 136.450324 -157.537658)
		(property "Reference" "R671"
			(at -64.6176 108.436918 0)
			(unlocked yes)
			(layer "F.SilkS")
			(effects
				(font
					(size 0.7874 0.5842)
					(thickness 0.1524)
				)
				(justify left)
			)
		)
		(property "Value" ""
			(at 0 0 0)
			(layer "F.Fab")
			(effects
				(font
					(size 1.27 1.27)
				)
			)
		)
		(duplicate_pad_numbers_are_jumpers no)
		(fp_line
			(start -0.7874 -0.4064)
			(end 0.7874 -0.4064)
			(stroke
				(width 0.1524)
				(type default)
			)
			(layer "F.SilkS")
		)
		(fp_line
			(start -0.7874 0.4064)
			(end -0.7874 -0.4064)
			(stroke
				(width 0.1524)
				(type default)
			)
			(layer "F.SilkS")
		)
		(fp_line
			(start 0.7874 -0.4064)
			(end 0.7874 0.4064)
			(stroke
				(width 0.1524)
				(type default)
			)
			(layer "F.SilkS")
		)
		(fp_line
			(start 0.7874 0.4064)
			(end -0.7874 0.4064)
			(stroke
				(width 0.1524)
				(type default)
			)
			(layer "F.SilkS")
		)
		(fp_poly
			(pts
				(xy -0.508 0.2794) (xy -0.508 0.2286) (xy -0.635 0.2286) (xy -0.635 -0.254) (xy -0.5334 -0.254)
				(xy -0.5334 -0.2794) (xy 0.5334 -0.2794) (xy 0.5334 -0.254) (xy 0.635 -0.254) (xy 0.635 0.254) (xy 0.5334 0.254)
				(xy 0.5334 0.2794)
			)
			(stroke
				(width 0)
				(type default)
			)
			(fill no)
			(layer "F.CrtYd")
		)
		(pad "1" smd rect
			(at 0.40005 0)
			(size 0.4572 0.508)
			(layers "F.Cu" "F.Mask" "F.Paste")
			(net "P3V3_NODE1")
		)
		(pad "2" smd rect
			(at -0.40005 0)
			(size 0.4572 0.508)
			(layers "F.Cu" "F.Mask" "F.Paste")
			(net "I2C_PSU3_SDA_MOS")
		)
	)
	(footprint ""
		(layer "F.Cu")
		(at 58.314336 -164.534596 -90)
		(property "Reference" "C846"
			(at -1.509776 0.121412 90)
			(unlocked yes)
			(layer "F.SilkS")
			(effects
				(font
					(size 0.7874 0.5842)
					(thickness 0.1524)
				)
				(justify left)
			)
		)
		(property "Value" ""
			(at 0 0 270)
			(layer "F.Fab")
			(effects
				(font
					(size 1.27 1.27)
				)
			)
		)
		(duplicate_pad_numbers_are_jumpers no)
		(fp_line
			(start -0.7874 0.4064)
			(end -0.7874 -0.4064)
			(stroke
				(width 0.1524)
				(type default)
			)
			(layer "F.SilkS")
		)
		(fp_line
			(start 0.7874 0.4064)
			(end -0.7874 0.4064)
			(stroke
				(width 0.1524)
				(type default)
			)
			(layer "F.SilkS")
		)
		(fp_line
			(start 0 0.381)
			(end 0 -0.381)
			(stroke
				(width 0.1524)
				(type default)
			)
			(layer "F.SilkS")
		)
		(fp_line
			(start -0.7874 -0.4064)
			(end 0.7874 -0.4064)
			(stroke
				(width 0.1524)
				(type default)
			)
			(layer "F.SilkS")
		)
		(fp_line
			(start 0.7874 -0.4064)
			(end 0.7874 0.4064)
			(stroke
				(width 0.1524)
				(type default)
			)
			(layer "F.SilkS")
		)
		(fp_poly
			(pts
				(xy -0.5334 0.254) (xy -0.635 0.254) (xy -0.635 0.2286) (xy -0.635 -0.254) (xy -0.5334 -0.254) (xy -0.5334 -0.2794)
				(xy 0.5334 -0.2794) (xy 0.5334 -0.254) (xy 0.635 -0.254) (xy 0.635 0.254) (xy 0.5334 0.254) (xy 0.5334 0.2794)
				(xy -0.508 0.2794) (xy -0.5334 0.2794)
			)
			(stroke
				(width 0)
				(type default)
			)
			(fill no)
			(layer "F.CrtYd")
		)
		(pad "1" smd rect
			(at 0.40005 0 270)
			(size 0.4572 0.508)
			(layers "F.Cu" "F.Mask" "F.Paste")
			(net "FM_CPLD_NODE1_P5V_EN")
		)
		(pad "2" smd rect
			(at -0.40005 0 270)
			(size 0.4572 0.508)
			(layers "F.Cu" "F.Mask" "F.Paste")
			(net "GND")
		)
	)
	(footprint ""
		(layer "F.Cu")
		(at 155.05176 -185.205624 -90)
		(property "Reference" "R897"
			(at -4.768088 -0.259588 90)
			(unlocked yes)
			(layer "F.SilkS")
			(effects
				(font
					(size 0.7874 0.5842)
					(thickness 0.1524)
				)
				(justify left)
			)
		)
		(property "Value" ""
			(at 0 0 270)
			(layer "F.Fab")
			(effects
				(font
					(size 1.27 1.27)
				)
			)
		)
		(duplicate_pad_numbers_are_jumpers no)
		(fp_line
			(start -0.7874 0.4064)
			(end -0.7874 -0.4064)
			(stroke
				(width 0.1524)
				(type default)
			)
			(layer "F.SilkS")
		)
		(fp_line
			(start 0.7874 0.4064)
			(end -0.7874 0.4064)
			(stroke
				(width 0.1524)
				(type default)
			)
			(layer "F.SilkS")
		)
		(fp_line
			(start -0.7874 -0.4064)
			(end 0.7874 -0.4064)
			(stroke
				(width 0.1524)
				(type default)
			)
			(layer "F.SilkS")
		)
		(fp_line
			(start 0.7874 -0.4064)
			(end 0.7874 0.4064)
			(stroke
				(width 0.1524)
				(type default)
			)
			(layer "F.SilkS")
		)
		(fp_poly
			(pts
				(xy -0.508 0.2794) (xy -0.508 0.2286) (xy -0.635 0.2286) (xy -0.635 -0.254) (xy -0.5334 -0.254)
				(xy -0.5334 -0.2794) (xy 0.5334 -0.2794) (xy 0.5334 -0.254) (xy 0.635 -0.254) (xy 0.635 0.254) (xy 0.5334 0.254)
				(xy 0.5334 0.2794)
			)
			(stroke
				(width 0)
				(type default)
			)
			(fill no)
			(layer "F.CrtYd")
		)
		(pad "1" smd rect
			(at 0.40005 0 270)
			(size 0.4572 0.508)
			(layers "F.Cu" "F.Mask" "F.Paste")
			(net "T12_NODE1_EN")
		)
		(pad "2" smd rect
			(at -0.40005 0 270)
			(size 0.4572 0.508)
			(layers "F.Cu" "F.Mask" "F.Paste")
			(net "T12_NODE1_EN_R")
		)
	)
)
